(kicad_pcb
	(version 20221018)
	(generator pcbnew)
	(general
    (thickness 0.908)
  )
	(paper "A4")
	(title_block
    (title "HDMI-MIPI Bridge")
    (date "2024-04-24")
    (rev "1.3.2")
		(comment 9 "footprints 19-26 of 121")
	)
	(layers
    (0 "F.Cu" signal)
    (1 "In1.Cu" signal)
    (2 "In2.Cu" signal)
    (31 "B.Cu" signal)
    (32 "B.Adhes" user "B.Adhesive")
    (33 "F.Adhes" user "F.Adhesive")
    (34 "B.Paste" user)
    (35 "F.Paste" user)
    (36 "B.SilkS" user "B.Silkscreen")
    (37 "F.SilkS" user "F.Silkscreen")
    (38 "B.Mask" user)
    (39 "F.Mask" user)
    (40 "Dwgs.User" user "User.Drawings")
    (41 "Cmts.User" user "User.Comments")
    (42 "Eco1.User" user "User.Eco1")
    (43 "Eco2.User" user "User.Eco2")
    (44 "Edge.Cuts" user)
    (45 "Margin" user)
    (46 "B.CrtYd" user "B.Courtyard")
    (47 "F.CrtYd" user "F.Courtyard")
    (48 "B.Fab" user)
    (49 "F.Fab" user)
  )
	(footprint "antmicro-footprints:R_0603_1608Metric" (layer "F.Cu")
    (at 163.79 116.15 -90)
    (descr "Resistor SMD 0603")
    (tags "resistor SMD 0603")
    (property "Author" "Antmicro")
    (property "Current" "1A")
    (property "License" "Apache-2.0")
    (property "MPN" "CR0603-J/-000ELF")
    (property "Manufacturer" "Bourns")
    (property "Public" "False")
    (property "Sheetfile" "channel2.kicad_sch")
    (property "Sheetname" "Channel 2")
    (property "Tolerance" "")
    (property "Val" "0R")
    (property "ki_description" "Zero Ohm Resistor, Jumper, 0603 [1608 Metric], Thick Film, 100 mW, 1 A, Surface Mount Device, CR")
    (property "ki_keywords" "0603, SMT, RESISTOR, PASSIVE")
    (attr smd)
    (fp_text reference "R18" (at 3.35 -0.21 -90) (layer "F.SilkS")
        (effects (font (size 0.7 0.7) (thickness 0.15)) (justify left bottom))
    )
    (fp_text value "R_0R_0603" (at 0 1.6 -90) (layer "F.Fab")
        (effects (font (size 0.7 0.7) (thickness 0.15)) (justify left bottom))
    )
    (fp_text user "License: Apache-2.0" (at -1.25 5.9 -90) (layer "F.Fab") hide
        (effects (font (size 0.7 0.7) (thickness 0.15)) (justify left bottom))
    )
    (fp_text user "Author: Antmicro" (at -1.25 4.9 -90) (layer "F.Fab") hide
        (effects (font (size 0.7 0.7) (thickness 0.15)) (justify left bottom))
    )
    (fp_text user "${REFERENCE}" (at -1.25 3.898 -90) (layer "F.Fab") hide
        (effects (font (size 0.7 0.7) (thickness 0.15)) (justify left bottom))
    )
    (fp_line (start -0.15 -0.4) (end 0.15 -0.4)
      (stroke (width 0.15) (type solid)) (layer "F.SilkS"))
    (fp_line (start -0.15 0.4) (end 0.15 0.4)
      (stroke (width 0.15) (type solid)) (layer "F.SilkS"))
    (fp_rect (start -1.25 -0.65) (end 1.25 0.65)
      (stroke (width 0.05) (type solid)) (fill none) (layer "F.CrtYd"))
    (fp_rect (start -0.8 -0.4) (end 0.8 0.4)
      (stroke (width 0.15) (type solid)) (fill none) (layer "F.Fab"))
    (pad "1" smd roundrect (at -0.7 0 270) (size 0.8 1) (layers "F.Cu" "F.Paste" "F.Mask") (roundrect_rratio 0.2)
      (net 22 "Net-(C31-Pad2)") (pintype "passive"))
    (pad "2" smd roundrect (at 0.7 0 270) (size 0.8 1) (layers "F.Cu" "F.Paste" "F.Mask") (roundrect_rratio 0.2)
      (net 33 "Net-(U4B-VDDC1)") (pintype "passive"))
  )
	(footprint "antmicro-footprints:C_0603_1608Metric" (layer "F.Cu")
    (at 139.96 106.97 180)
    (descr "Capacitor SMD 0603")
    (tags "capacitor 0603")
    (property "Author" "Antmicro")
    (property "Dielectric" "")
    (property "License" "Apache-2.0")
    (property "MPN" "C1608X5R1V475M080AC")
    (property "Manufacturer" "TDK")
    (property "Public" "False")
    (property "Sheetfile" "channel1.kicad_sch")
    (property "Sheetname" "Channel 1")
    (property "Val" "4u7")
    (property "Voltage" "")
    (property "ki_description" "SMD Multilayer Ceramic Capacitor, 4.7 µF, 35 V, 0603 [1608 Metric], ± 20%, X5R, C")
    (property "ki_keywords" "0603, SMT, CAPACITOR, PASSIVE, CERAMIC, MLCC")
    (attr smd)
    (fp_text reference "C9" (at 1.32 -0.12) (layer "F.SilkS")
        (effects (font (size 0.65 0.65) (thickness 0.13)) (justify right bottom))
    )
    (fp_text value "C_4u7_0603" (at 0 1.6) (layer "F.Fab")
        (effects (font (size 0.65 0.65) (thickness 0.13)) (justify right bottom))
    )
    (fp_text user "Author: Antmicro" (at -1.682 4.894) (layer "F.Fab") hide
        (effects (font (size 0.7 0.7) (thickness 0.15)) (justify right bottom))
    )
    (fp_text user "License: Apache-2.0" (at -1.682 5.895) (layer "F.Fab") hide
        (effects (font (size 0.7 0.7) (thickness 0.15)) (justify right bottom))
    )
    (fp_text user "${REFERENCE}" (at -1.682 3.895) (layer "F.Fab") hide
        (effects (font (size 0.7 0.7) (thickness 0.15)) (justify right bottom))
    )
    (fp_line (start -0.15 -0.4) (end 0.15 -0.4)
      (stroke (width 0.15) (type solid)) (layer "F.SilkS"))
    (fp_line (start -0.15 0.4) (end 0.15 0.4)
      (stroke (width 0.15) (type solid)) (layer "F.SilkS"))
    (fp_rect (start -1.25 -0.65) (end 1.25 0.65)
      (stroke (width 0.05) (type solid)) (fill none) (layer "F.CrtYd"))
    (fp_rect (start -0.8 -0.4) (end 0.8 0.4)
      (stroke (width 0.15) (type solid)) (fill none) (layer "F.Fab"))
    (pad "1" smd roundrect (at -0.7 0 180) (size 0.8 1) (layers "F.Cu" "F.Paste" "F.Mask") (roundrect_rratio 0.2)
      (net 2 "GND") (pintype "passive"))
    (pad "2" smd roundrect (at 0.7 0 180) (size 0.8 1) (layers "F.Cu" "F.Paste" "F.Mask") (roundrect_rratio 0.2)
      (net 6 "Net-(C5-Pad1)") (pintype "passive"))
  )
	(footprint "antmicro-footprints:FB_0805_2012Metric" (layer "F.Cu")
    (at 166.5 115.55)
    (descr "FERRITE BEAD 0805")
    (tags "FERRITE BEAD 0805")
    (property "Author" "Antmicro")
    (property "Current" "")
    (property "License" "Apache-2.0")
    (property "MPN" "742792096")
    (property "Manufacturer" "Würth Elektronik")
    (property "Public" "False")
    (property "Sheetfile" "channel2.kicad_sch")
    (property "Sheetname" "Channel 2")
    (property "Val" "1kZ/0.8A")
    (property "ki_description" "Ferrite Beads WE-CBF 0805 100MHz 1kOhm 1A, High Current")
    (property "ki_keywords" "FERRITE BEAD, PASSIVE")
    (attr smd)
    (fp_text reference "FB10" (at -1.41 1.61) (layer "F.SilkS")
        (effects (font (size 0.65 0.65) (thickness 0.13)) (justify left bottom))
    )
    (fp_text value "FB_1kZ_0.8A_WE-CBF_0805" (at 0 1.8) (layer "F.Fab")
        (effects (font (size 0.65 0.65) (thickness 0.13)) (justify left bottom))
    )
    (fp_text user "${REFERENCE}" (at -1.9 3.1) (layer "F.Fab") hide
        (effects (font (size 0.7 0.7) (thickness 0.15)) (justify left bottom))
    )
    (fp_text user "Author: Antmicro" (at -1.9 4.4) (layer "F.Fab") hide
        (effects (font (size 0.7 0.7) (thickness 0.15)) (justify left bottom))
    )
    (fp_text user "License: Apache-2.0" (at -1.9 5.75) (layer "F.Fab") hide
        (effects (font (size 0.7 0.7) (thickness 0.15)) (justify left bottom))
    )
    (fp_line (start -0.319 0.698) (end 0.281 0.698)
      (stroke (width 0.15) (type solid)) (layer "F.SilkS"))
    (fp_line (start -0.299 -0.698) (end 0.299 -0.698)
      (stroke (width 0.15) (type solid)) (layer "F.SilkS"))
    (fp_rect (start 1.95 -0.9) (end -1.95 0.9)
      (stroke (width 0.05) (type default)) (fill none) (layer "F.CrtYd"))
    (fp_line (start -0.948 -0.681) (end 0.948 -0.681)
      (stroke (width 0.15) (type solid)) (layer "F.Fab"))
    (fp_line (start -0.948 -0.676) (end -0.948 0.676)
      (stroke (width 0.15) (type solid)) (layer "F.Fab"))
    (fp_line (start -0.948 0.681) (end 0.948 0.681)
      (stroke (width 0.15) (type solid)) (layer "F.Fab"))
    (fp_line (start 0.948 -0.676) (end 0.948 0.676)
      (stroke (width 0.15) (type solid)) (layer "F.Fab"))
    (pad "1" smd roundrect (at -1.1 0) (size 1.2 1.3) (layers "F.Cu" "F.Paste" "F.Mask") (roundrect_rratio 0.25)
      (net 110 "Net-(C49-Pad1)") (pintype "passive"))
    (pad "2" smd roundrect (at 1.1 0) (size 1.2 1.3) (layers "F.Cu" "F.Paste" "F.Mask") (roundrect_rratio 0.25)
      (net 25 "CH2_1V2") (pintype "passive"))
  )
	(footprint "antmicro-footprints:FB_0805_2012Metric" (layer "F.Cu")
    (at 166.6 112.65 -90)
    (descr "FERRITE BEAD 0805")
    (tags "FERRITE BEAD 0805")
    (property "Author" "Antmicro")
    (property "Current" "")
    (property "License" "Apache-2.0")
    (property "MPN" "742792096")
    (property "Manufacturer" "Würth Elektronik")
    (property "Public" "False")
    (property "Sheetfile" "channel2.kicad_sch")
    (property "Sheetname" "Channel 2")
    (property "Val" "1kZ/0.8A")
    (property "ki_description" "Ferrite Beads WE-CBF 0805 100MHz 1kOhm 1A, High Current")
    (property "ki_keywords" "FERRITE BEAD, PASSIVE")
    (attr smd)
    (fp_text reference "FB8" (at 1.05 -1.79 -90) (layer "F.SilkS")
        (effects (font (size 0.65 0.65) (thickness 0.13)) (justify left bottom))
    )
    (fp_text value "FB_1kZ_0.8A_WE-CBF_0805" (at 0 1.8 -90) (layer "F.Fab")
        (effects (font (size 0.65 0.65) (thickness 0.13)) (justify left bottom))
    )
    (fp_text user "${REFERENCE}" (at -1.9 3.1 -90) (layer "F.Fab") hide
        (effects (font (size 0.7 0.7) (thickness 0.15)) (justify left bottom))
    )
    (fp_text user "Author: Antmicro" (at -1.9 4.4 -90) (layer "F.Fab") hide
        (effects (font (size 0.7 0.7) (thickness 0.15)) (justify left bottom))
    )
    (fp_text user "License: Apache-2.0" (at -1.9 5.75 -90) (layer "F.Fab") hide
        (effects (font (size 0.7 0.7) (thickness 0.15)) (justify left bottom))
    )
    (fp_line (start -0.319 0.698) (end 0.281 0.698)
      (stroke (width 0.15) (type solid)) (layer "F.SilkS"))
    (fp_line (start -0.299 -0.698) (end 0.299 -0.698)
      (stroke (width 0.15) (type solid)) (layer "F.SilkS"))
    (fp_rect (start 1.95 -0.9) (end -1.95 0.9)
      (stroke (width 0.05) (type default)) (fill none) (layer "F.CrtYd"))
    (fp_line (start -0.948 -0.681) (end 0.948 -0.681)
      (stroke (width 0.15) (type solid)) (layer "F.Fab"))
    (fp_line (start -0.948 -0.676) (end -0.948 0.676)
      (stroke (width 0.15) (type solid)) (layer "F.Fab"))
    (fp_line (start -0.948 0.681) (end 0.948 0.681)
      (stroke (width 0.15) (type solid)) (layer "F.Fab"))
    (fp_line (start 0.948 -0.676) (end 0.948 0.676)
      (stroke (width 0.15) (type solid)) (layer "F.Fab"))
    (pad "1" smd roundrect (at -1.1 0 270) (size 1.2 1.3) (layers "F.Cu" "F.Paste" "F.Mask") (roundrect_rratio 0.25)
      (net 32 "Net-(U4B-AVDD25)") (pintype "passive"))
    (pad "2" smd roundrect (at 1.1 0 270) (size 1.2 1.3) (layers "F.Cu" "F.Paste" "F.Mask") (roundrect_rratio 0.25)
      (net 24 "CH2_2V5") (pintype "passive"))
  )
	(footprint "antmicro-footprints:C_0402_1005Metric" (layer "F.Cu")
    (at 143.84 106.25)
    (descr "Capacitor SMD 0402")
    (tags "capacitor SMD 0402")
    (property "Author" "Antmicro")
    (property "Dielectric" "X5R")
    (property "License" "Apache-2.0")
    (property "MPN" "GRM155R61H104KE14D")
    (property "Manufacturer" "Murata")
    (property "Public" "False")
    (property "Sheetfile" "channel1.kicad_sch")
    (property "Sheetname" "Channel 1")
    (property "Val" "100n")
    (property "Voltage" "50V")
    (property "ki_description" "SMD Multilayer Ceramic Capacitor, 0.1 µF, 50 V, 0402 [1005 Metric], ± 10%, X5R, GRM Series")
    (property "ki_keywords" "0402, SMT, CAPACITOR, PASSIVE, CERAMIC, MLCC")
    (attr smd)
    (fp_text reference "C14" (at -0.84 -0.45) (layer "F.SilkS")
        (effects (font (size 0.65 0.65) (thickness 0.13)) (justify left bottom))
    )
    (fp_text value "C_100n_0402" (at 0 1.4) (layer "F.Fab")
        (effects (font (size 0.65 0.65) (thickness 0.13)) (justify left bottom))
    )
    (fp_text user "License: Apache-2.0" (at -0.932 5.17) (layer "F.Fab") hide
        (effects (font (size 0.7 0.7) (thickness 0.15)) (justify left bottom))
    )
    (fp_text user "${REFERENCE}" (at -0.932 3.168) (layer "F.Fab") hide
        (effects (font (size 0.7 0.7) (thickness 0.15)) (justify left bottom))
    )
    (fp_text user "Author: Antmicro" (at -0.932 4.17) (layer "F.Fab") hide
        (effects (font (size 0.7 0.7) (thickness 0.15)) (justify left bottom))
    )
    (fp_rect (start -0.925 -0.47) (end 0.925 0.47)
      (stroke (width 0.05) (type default)) (fill none) (layer "F.CrtYd"))
    (fp_line (start -0.494 -0.25) (end 0.504 -0.25)
      (stroke (width 0.15) (type solid)) (layer "F.Fab"))
    (fp_line (start -0.494 0.248) (end -0.494 -0.25)
      (stroke (width 0.15) (type solid)) (layer "F.Fab"))
    (fp_line (start 0.504 -0.25) (end 0.504 0.248)
      (stroke (width 0.15) (type solid)) (layer "F.Fab"))
    (fp_line (start 0.504 0.248) (end -0.494 0.248)
      (stroke (width 0.15) (type solid)) (layer "F.Fab"))
    (pad "1" smd roundrect (at -0.48 0) (size 0.59 0.64) (layers "F.Cu" "F.Paste" "F.Mask") (roundrect_rratio 0.25)
      (net 9 "+3V3") (pintype "passive"))
    (pad "2" smd roundrect (at 0.48 0) (size 0.59 0.64) (layers "F.Cu" "F.Paste" "F.Mask") (roundrect_rratio 0.25)
      (net 2 "GND") (pintype "passive"))
  )
	(footprint "antmicro-footprints:C_0402_1005Metric" (layer "F.Cu")
    (at 154.985 113.45)
    (descr "Capacitor SMD 0402")
    (tags "capacitor SMD 0402")
    (property "Author" "Antmicro")
    (property "Dielectric" "X5R")
    (property "License" "Apache-2.0")
    (property "MPN" "GRM155R61H104KE14D")
    (property "Manufacturer" "Murata")
    (property "Public" "False")
    (property "Sheetfile" "channel2.kicad_sch")
    (property "Sheetname" "Channel 2")
    (property "Val" "100n")
    (property "Voltage" "50V")
    (property "ki_description" "SMD Multilayer Ceramic Capacitor, 0.1 µF, 50 V, 0402 [1005 Metric], ± 10%, X5R, GRM Series")
    (property "ki_keywords" "0402, SMT, CAPACITOR, PASSIVE, CERAMIC, MLCC")
    (attr smd)
    (fp_text reference "C33" (at -1.545 7.62) (layer "F.SilkS")
        (effects (font (size 0.65 0.65) (thickness 0.13)) (justify left bottom))
    )
    (fp_text value "C_100n_0402" (at 0 1.4) (layer "F.Fab")
        (effects (font (size 0.65 0.65) (thickness 0.13)) (justify left bottom))
    )
    (fp_text user "License: Apache-2.0" (at -0.932 5.17) (layer "F.Fab") hide
        (effects (font (size 0.7 0.7) (thickness 0.15)) (justify left bottom))
    )
    (fp_text user "Author: Antmicro" (at -0.932 4.17) (layer "F.Fab") hide
        (effects (font (size 0.7 0.7) (thickness 0.15)) (justify left bottom))
    )
    (fp_text user "${REFERENCE}" (at -0.932 3.168) (layer "F.Fab") hide
        (effects (font (size 0.7 0.7) (thickness 0.15)) (justify left bottom))
    )
    (fp_rect (start -0.925 -0.47) (end 0.925 0.47)
      (stroke (width 0.05) (type default)) (fill none) (layer "F.CrtYd"))
    (fp_line (start -0.494 -0.25) (end 0.504 -0.25)
      (stroke (width 0.15) (type solid)) (layer "F.Fab"))
    (fp_line (start -0.494 0.248) (end -0.494 -0.25)
      (stroke (width 0.15) (type solid)) (layer "F.Fab"))
    (fp_line (start 0.504 -0.25) (end 0.504 0.248)
      (stroke (width 0.15) (type solid)) (layer "F.Fab"))
    (fp_line (start 0.504 0.248) (end -0.494 0.248)
      (stroke (width 0.15) (type solid)) (layer "F.Fab"))
    (pad "1" smd roundrect (at -0.48 0) (size 0.59 0.64) (layers "F.Cu" "F.Paste" "F.Mask") (roundrect_rratio 0.25)
      (net 2 "GND") (pintype "passive"))
    (pad "2" smd roundrect (at 0.48 0) (size 0.59 0.64) (layers "F.Cu" "F.Paste" "F.Mask") (roundrect_rratio 0.25)
      (net 26 "Net-(U4B-VDDIO2)") (pintype "passive"))
  )
	(footprint "antmicro-footprints:C_0402_1005Metric" (layer "F.Cu")
    (at 129.53 111.8 90)
    (descr "Capacitor SMD 0402")
    (tags "capacitor SMD 0402")
    (property "Author" "Antmicro")
    (property "Dielectric" "C0G")
    (property "License" "Apache-2.0")
    (property "MPN" "C0402C470J5GACTU")
    (property "Manufacturer" "KEMET")
    (property "Public" "False")
    (property "Sheetfile" "channel1.kicad_sch")
    (property "Sheetname" "Channel 1")
    (property "Val" "47p")
    (property "Voltage" "")
    (property "ki_description" "SMD Multilayer Ceramic Capacitor, 47 pF, 50 V, 0402 [1005 Metric], ± 5%, C0G / NP0, C Series KEMET")
    (property "ki_keywords" "0402, SMT, CAPACITOR, PASSIVE, CERAMIC, MLCC")
    (attr smd)
    (fp_text reference "C21" (at 0.9 0.27 90) (layer "F.SilkS")
        (effects (font (size 0.65 0.65) (thickness 0.13)) (justify left bottom))
    )
    (fp_text value "C_47p_0402" (at 0 1.4 90) (layer "F.Fab")
        (effects (font (size 0.65 0.65) (thickness 0.13)) (justify left bottom))
    )
    (fp_text user "License: Apache-2.0" (at -0.932 5.17 90) (layer "F.Fab") hide
        (effects (font (size 0.7 0.7) (thickness 0.15)) (justify left bottom))
    )
    (fp_text user "${REFERENCE}" (at -0.932 3.168 90) (layer "F.Fab") hide
        (effects (font (size 0.7 0.7) (thickness 0.15)) (justify left bottom))
    )
    (fp_text user "Author: Antmicro" (at -0.932 4.17 90) (layer "F.Fab") hide
        (effects (font (size 0.7 0.7) (thickness 0.15)) (justify left bottom))
    )
    (fp_rect (start -0.925 -0.47) (end 0.925 0.47)
      (stroke (width 0.05) (type default)) (fill none) (layer "F.CrtYd"))
    (fp_line (start -0.494 -0.25) (end 0.504 -0.25)
      (stroke (width 0.15) (type solid)) (layer "F.Fab"))
    (fp_line (start -0.494 0.248) (end -0.494 -0.25)
      (stroke (width 0.15) (type solid)) (layer "F.Fab"))
    (fp_line (start 0.504 -0.25) (end 0.504 0.248)
      (stroke (width 0.15) (type solid)) (layer "F.Fab"))
    (fp_line (start 0.504 0.248) (end -0.494 0.248)
      (stroke (width 0.15) (type solid)) (layer "F.Fab"))
    (pad "1" smd roundrect (at -0.48 0 90) (size 0.59 0.64) (layers "F.Cu" "F.Paste" "F.Mask") (roundrect_rratio 0.25)
      (net 2 "GND") (pintype "passive"))
    (pad "2" smd roundrect (at 0.48 0 90) (size 0.59 0.64) (layers "F.Cu" "F.Paste" "F.Mask") (roundrect_rratio 0.25)
      (net 13 "Net-(Y1-OUT)") (pintype "passive"))
  )
	(footprint "antmicro-footprints:R_0402_1005Metric" (layer "F.Cu")
    (at 139.28 102.21 -90)
    (descr "Resistor SMD 0402")
    (tags "resistor SMD 0402")
    (property "Author" "Antmicro")
    (property "License" "Apache-2.0")
    (property "MPN" "CR0402-FX-1002GLF")
    (property "Manufacturer" "Bourns")
    (property "Public" "False")
    (property "Sheetfile" "channel1.kicad_sch")
    (property "Sheetname" "Channel 1")
    (property "Tolerance" "1%")
    (property "Val" "10k")
    (property "ki_description" "SMD Chip Resistor, 10 kohm, ± 1%, 62.5 mW, 0402 [1005 Metric], Thick Film, General Purpose")
    (property "ki_keywords" "0402, SMT, RESISTOR, PASSIVE")
    (attr smd)
    (fp_text reference "R11" (at -3.25 11.64 -90) (layer "F.SilkS")
        (effects (font (size 0.65 0.65) (thickness 0.13)) (justify left bottom))
    )
    (fp_text value "R_10k_0402" (at 0 1.4 -90) (layer "F.Fab")
        (effects (font (size 0.65 0.65) (thickness 0.13)) (justify left bottom))
    )
    (fp_text user "License: Apache-2.0" (at -0.95 5.169 -90) (layer "F.Fab") hide
        (effects (font (size 0.7 0.7) (thickness 0.15)) (justify left bottom))
    )
    (fp_text user "${REFERENCE}" (at -0.95 3.168 -90) (layer "F.Fab") hide
        (effects (font (size 0.7 0.7) (thickness 0.15)) (justify left bottom))
    )
    (fp_text user "Author: Antmicro" (at -0.95 4.169 -90) (layer "F.Fab") hide
        (effects (font (size 0.7 0.7) (thickness 0.15)) (justify left bottom))
    )
    (fp_rect (start -0.925 -0.47) (end 0.925 0.47)
      (stroke (width 0.05) (type default)) (fill none) (layer "F.CrtYd"))
    (fp_rect (start -0.5 -0.25) (end 0.5 0.25)
      (stroke (width 0.15) (type solid)) (fill none) (layer "F.Fab"))
    (pad "1" smd roundrect (at -0.48 0 270) (size 0.59 0.64) (layers "F.Cu" "F.Paste" "F.Mask") (roundrect_rratio 0.25)
      (net 84 "/Channel 1/HDMI1_DDC_SCL") (pintype "passive"))
    (pad "2" smd roundrect (at 0.48 0 270) (size 0.59 0.64) (layers "F.Cu" "F.Paste" "F.Mask") (roundrect_rratio 0.25)
      (net 14 "+5V") (pintype "passive"))
  )
)
